(kicad_pcb
	(version 20260206)
	(generator "pcbnew")
	(generator_version "10.0")
	(general
		(thickness 1.6)
		(legacy_teardrops no)
	)
	(paper "A4")
	(title_block
		(title "04192023_DAF0TMB3IC0_F0TG_MB_C_brd_V02_OCP.brd")
		(comment 1 "Grand Teton / footprints 6173-6178 of 8354")
	)
	(layers
		(0 "F.Cu" signal "TOP")
		(4 "In1.Cu" signal "GND")
		(6 "In2.Cu" signal "IN1")
		(8 "In3.Cu" signal "GND1")
		(10 "In4.Cu" signal "IN2")
		(12 "In5.Cu" signal "GND2")
		(14 "In6.Cu" signal "IN3")
		(16 "In7.Cu" signal "GND3")
		(18 "In8.Cu" signal "VCC")
		(20 "In9.Cu" signal "VCC1")
		(22 "In10.Cu" signal "GND4")
		(24 "In11.Cu" signal "IN4")
		(26 "In12.Cu" signal "GND5")
		(28 "In13.Cu" signal "IN5")
		(30 "In14.Cu" signal "GND6")
		(32 "In15.Cu" signal "IN6")
		(34 "In16.Cu" signal "GND7")
		(2 "B.Cu" signal "BOTTOM")
		(9 "F.Adhes" user "F.Adhesive")
		(11 "B.Adhes" user "B.Adhesive")
		(13 "F.Paste" user "Package Geometry/Pastemask Top")
		(15 "B.Paste" user "Package Geometry/Pastemask Bottom")
		(5 "F.SilkS" user "Ref Des/Silkscreen Top")
		(7 "B.SilkS" user "Ref Des/Silkscreen Bottom")
		(1 "F.Mask" user "Board Geometry/Soldermask Top")
		(3 "B.Mask" user "Board Geometry/Soldermask Bottom")
		(17 "Dwgs.User" user "User.Drawings")
		(19 "Cmts.User" user "User.Comments")
		(21 "Eco1.User" user "User.Eco1")
		(23 "Eco2.User" user "User.Eco2")
		(25 "Edge.Cuts" user "Board Geometry/Outline")
		(27 "Margin" user)
		(31 "F.CrtYd" user "Package Geometry/Place Bound Top")
		(29 "B.CrtYd" user "Package Geometry/Place Bound Bottom")
		(35 "F.Fab" user "Ref Des/Assembly Top")
		(33 "B.Fab" user "Ref Des/Assembly Bottom")
	)
	(footprint ""
		(layer "B.Cu")
		(at 350.318832 -398.942052 90)
		(property "Reference" "C648"
			(at 0 0 90)
			(layer "B.SilkS")
			(hide yes)
			(effects
				(font
					(size 1.27 1.27)
				)
				(justify mirror)
			)
		)
		(property "Value" ""
			(at 0 0 90)
			(layer "B.Fab")
			(effects
				(font
					(size 1.27 1.27)
				)
				(justify mirror)
			)
		)
		(duplicate_pad_numbers_are_jumpers no)
		(fp_line
			(start 0.7874 -0.4064)
			(end -0.7874 -0.4064)
			(stroke
				(width 0.1524)
				(type default)
			)
			(layer "B.SilkS")
		)
		(fp_line
			(start -0.7874 -0.4064)
			(end -0.7874 0.4064)
			(stroke
				(width 0.1524)
				(type default)
			)
			(layer "B.SilkS")
		)
		(fp_line
			(start 0.7874 0.4064)
			(end 0.7874 -0.4064)
			(stroke
				(width 0.1524)
				(type default)
			)
			(layer "B.SilkS")
		)
		(fp_line
			(start -0.7874 0.4064)
			(end 0.7874 0.4064)
			(stroke
				(width 0.1524)
				(type default)
			)
			(layer "B.SilkS")
		)
		(fp_line
			(start 0.67945 -0.305054)
			(end 0.12065 -0.305054)
			(stroke
				(width 0.1)
				(type default)
			)
			(layer "B.Fab")
		)
		(fp_line
			(start 0.12065 -0.305054)
			(end 0.12065 -0.2794)
			(stroke
				(width 0.1)
				(type default)
			)
			(layer "B.Fab")
		)
		(fp_line
			(start -0.12065 -0.3048)
			(end -0.67945 -0.3048)
			(stroke
				(width 0.1)
				(type default)
			)
			(layer "B.Fab")
		)
		(fp_line
			(start -0.67945 -0.3048)
			(end -0.67945 0.3048)
			(stroke
				(width 0.1)
				(type default)
			)
			(layer "B.Fab")
		)
		(fp_line
			(start 0.12065 -0.2794)
			(end -0.12065 -0.2794)
			(stroke
				(width 0.1)
				(type default)
			)
			(layer "B.Fab")
		)
		(fp_line
			(start -0.12065 -0.2794)
			(end -0.12065 -0.3048)
			(stroke
				(width 0.1)
				(type default)
			)
			(layer "B.Fab")
		)
		(fp_line
			(start 0.12065 0.2794)
			(end 0.12065 0.3048)
			(stroke
				(width 0.1)
				(type default)
			)
			(layer "B.Fab")
		)
		(fp_line
			(start -0.120396 0.2794)
			(end 0.12065 0.2794)
			(stroke
				(width 0.1)
				(type default)
			)
			(layer "B.Fab")
		)
		(fp_line
			(start 0.67945 0.3048)
			(end 0.67945 -0.305054)
			(stroke
				(width 0.1)
				(type default)
			)
			(layer "B.Fab")
		)
		(fp_line
			(start 0.12065 0.3048)
			(end 0.67945 0.3048)
			(stroke
				(width 0.1)
				(type default)
			)
			(layer "B.Fab")
		)
		(fp_line
			(start -0.120396 0.3048)
			(end -0.120396 0.2794)
			(stroke
				(width 0.1)
				(type default)
			)
			(layer "B.Fab")
		)
		(fp_line
			(start -0.67945 0.3048)
			(end -0.120396 0.3048)
			(stroke
				(width 0.1)
				(type default)
			)
			(layer "B.Fab")
		)
		(pad "1" smd circle
			(at 0.40005 0 270)
			(size 0 0)
			(layers "B.Cu" "B.Mask" "B.Paste")
			(net "P0V9_CPU0_RT1_2A")
		)
		(pad "2" smd circle
			(at -0.40005 0 270)
			(size 0 0)
			(layers "B.Cu" "B.Mask" "B.Paste")
			(net "GND")
		)
	)
	(footprint ""
		(layer "B.Cu")
		(at 171.972224 -192.66027 180)
		(property "Reference" "C532"
			(at 0 0 0)
			(layer "B.SilkS")
			(hide yes)
			(effects
				(font
					(size 1.27 1.27)
				)
				(justify mirror)
			)
		)
		(property "Value" ""
			(at 0 0 0)
			(layer "B.Fab")
			(effects
				(font
					(size 1.27 1.27)
				)
				(justify mirror)
			)
		)
		(duplicate_pad_numbers_are_jumpers no)
		(fp_line
			(start 1.524 0.762)
			(end 1.524 -0.762)
			(stroke
				(width 0.1524)
				(type default)
			)
			(layer "B.SilkS")
		)
		(fp_line
			(start 1.524 -0.762)
			(end -1.524 -0.762)
			(stroke
				(width 0.1524)
				(type default)
			)
			(layer "B.SilkS")
		)
		(fp_line
			(start -1.524 0.762)
			(end 1.524 0.762)
			(stroke
				(width 0.1524)
				(type default)
			)
			(layer "B.SilkS")
		)
		(fp_line
			(start -1.524 -0.762)
			(end -1.524 0.762)
			(stroke
				(width 0.1524)
				(type default)
			)
			(layer "B.SilkS")
		)
		(fp_line
			(start 1.1049 0.724916)
			(end -1.1049 0.724916)
			(stroke
				(width 0.1)
				(type default)
			)
			(layer "B.Fab")
		)
		(fp_line
			(start 1.1049 -0.724916)
			(end 1.1049 0.724916)
			(stroke
				(width 0.1)
				(type default)
			)
			(layer "B.Fab")
		)
		(fp_line
			(start -1.1049 0.724916)
			(end -1.1049 -0.724916)
			(stroke
				(width 0.1)
				(type default)
			)
			(layer "B.Fab")
		)
		(fp_line
			(start -1.1049 -0.724916)
			(end 1.1049 -0.724916)
			(stroke
				(width 0.1)
				(type default)
			)
			(layer "B.Fab")
		)
		(pad "1" smd rect
			(at 0.889 0 180)
			(size 1.016 1.27)
			(layers "B.Cu" "B.Mask" "B.Paste")
			(net "P12V_MEM_CPU1")
		)
		(pad "2" smd rect
			(at -0.889 0 180)
			(size 1.016 1.27)
			(layers "B.Cu" "B.Mask" "B.Paste")
			(net "GND")
		)
	)
	(footprint ""
		(layer "B.Cu")
		(at 404.475696 -344.300302)
		(property "Reference" "U101"
			(at 5.969 -0.980948 0)
			(unlocked yes)
			(layer "B.SilkS")
			(effects
				(font
					(size 0.7874 0.5842)
					(thickness 0.1524)
				)
				(justify left mirror)
			)
		)
		(property "Value" ""
			(at 0 0 0)
			(layer "B.Fab")
			(effects
				(font
					(size 1.27 1.27)
				)
				(justify mirror)
			)
		)
		(duplicate_pad_numbers_are_jumpers no)
		(fp_line
			(start -2.0574 -1.651)
			(end -2.0574 1.651)
			(stroke
				(width 0.1524)
				(type default)
			)
			(layer "B.SilkS")
		)
		(fp_line
			(start -2.0574 1.651)
			(end 2.0574 1.651)
			(stroke
				(width 0.1524)
				(type default)
			)
			(layer "B.SilkS")
		)
		(fp_line
			(start -0.381 -1.651)
			(end -2.0574 -1.651)
			(stroke
				(width 0.1524)
				(type default)
			)
			(layer "B.SilkS")
		)
		(fp_line
			(start 0 -1.016)
			(end -0.381 -1.651)
			(stroke
				(width 0.1524)
				(type default)
			)
			(layer "B.SilkS")
		)
		(fp_line
			(start 0.381 -1.651)
			(end 0 -1.016)
			(stroke
				(width 0.1524)
				(type default)
			)
			(layer "B.SilkS")
		)
		(fp_line
			(start 2.0574 -1.651)
			(end 0.381 -1.651)
			(stroke
				(width 0.1524)
				(type default)
			)
			(layer "B.SilkS")
		)
		(fp_line
			(start 2.0574 1.651)
			(end 2.0574 -1.651)
			(stroke
				(width 0.1524)
				(type default)
			)
			(layer "B.SilkS")
		)
		(fp_poly
			(pts
				(xy 2.159 -1.016) (xy 2.71272 -0.719328) (xy 2.71272 -1.344168)
			)
			(stroke
				(width 0)
				(type default)
			)
			(fill yes)
			(layer "B.SilkS")
		)
		(fp_line
			(start -1.599946 -1.199896)
			(end -1.599946 1.199896)
			(stroke
				(width 0.1)
				(type default)
			)
			(layer "B.Fab")
		)
		(fp_line
			(start -1.599946 1.199896)
			(end -0.899922 1.199896)
			(stroke
				(width 0.1)
				(type default)
			)
			(layer "B.Fab")
		)
		(fp_line
			(start -0.899922 -1.549908)
			(end -0.899922 -1.199896)
			(stroke
				(width 0.1)
				(type default)
			)
			(layer "B.Fab")
		)
		(fp_line
			(start -0.899922 -1.199896)
			(end -1.599946 -1.199896)
			(stroke
				(width 0.1)
				(type default)
			)
			(layer "B.Fab")
		)
		(fp_line
			(start -0.899922 1.199896)
			(end -0.899922 1.549908)
			(stroke
				(width 0.1)
				(type default)
			)
			(layer "B.Fab")
		)
		(fp_line
			(start -0.899922 1.549908)
			(end 0.899922 1.549908)
			(stroke
				(width 0.1)
				(type default)
			)
			(layer "B.Fab")
		)
		(fp_line
			(start 0.899922 -1.549908)
			(end -0.899922 -1.549908)
			(stroke
				(width 0.1)
				(type default)
			)
			(layer "B.Fab")
		)
		(fp_line
			(start 0.899922 -1.199896)
			(end 0.899922 -1.549908)
			(stroke
				(width 0.1)
				(type default)
			)
			(layer "B.Fab")
		)
		(fp_line
			(start 0.899922 1.199896)
			(end 1.599946 1.199896)
			(stroke
				(width 0.1)
				(type default)
			)
			(layer "B.Fab")
		)
		(fp_line
			(start 0.899922 1.549908)
			(end 0.899922 1.199896)
			(stroke
				(width 0.1)
				(type default)
			)
			(layer "B.Fab")
		)
		(fp_line
			(start 1.599946 -1.199896)
			(end 0.899922 -1.199896)
			(stroke
				(width 0.1)
				(type default)
			)
			(layer "B.Fab")
		)
		(fp_line
			(start 1.599946 1.199896)
			(end 1.599946 -1.199896)
			(stroke
				(width 0.1)
				(type default)
			)
			(layer "B.Fab")
		)
		(fp_poly
			(pts
				(xy 2.71272 -0.719328) (xy 2.71272 -1.344168) (xy 2.159 -1.016)
			)
			(stroke
				(width 0)
				(type default)
			)
			(fill yes)
			(layer "B.Fab")
		)
		(pad "1" smd rect
			(at 1.225042 -0.94996 270)
			(size 0.5588 1.3462)
			(layers "B.Cu" "B.Mask" "B.Paste")
			(net "Net_10729")
		)
		(pad "2" smd rect
			(at 1.225042 0 270)
			(size 0.5588 1.3462)
			(layers "B.Cu" "B.Mask" "B.Paste")
			(net "FM_BIOS_POST_CMPLT_N")
		)
		(pad "3" smd rect
			(at 1.225042 0.94996 270)
			(size 0.5588 1.3462)
			(layers "B.Cu" "B.Mask" "B.Paste")
			(net "GND")
		)
		(pad "4" smd rect
			(at -1.225042 0.94996 270)
			(size 0.5588 1.3462)
			(layers "B.Cu" "B.Mask" "B.Paste")
			(net "FM_BIOS_POST_CMPLT_BUF_R1_N")
		)
		(pad "5" smd rect
			(at -1.225042 -0.94996 270)
			(size 0.5588 1.3462)
			(layers "B.Cu" "B.Mask" "B.Paste")
			(net "PVDD18_S5_P0")
		)
	)
	(footprint ""
		(layer "B.Cu")
		(at 185.201814 -357.667052)
		(property "Reference" "PC521_1"
			(at 0 0 0)
			(layer "B.SilkS")
			(hide yes)
			(effects
				(font
					(size 1.27 1.27)
				)
				(justify mirror)
			)
		)
		(property "Value" ""
			(at 0 0 0)
			(layer "B.Fab")
			(effects
				(font
					(size 1.27 1.27)
				)
				(justify mirror)
			)
		)
		(duplicate_pad_numbers_are_jumpers no)
		(fp_line
			(start -1.524 -0.762)
			(end -1.524 0.762)
			(stroke
				(width 0.1524)
				(type default)
			)
			(layer "B.SilkS")
		)
		(fp_line
			(start -1.524 0.762)
			(end 1.524 0.762)
			(stroke
				(width 0.1524)
				(type default)
			)
			(layer "B.SilkS")
		)
		(fp_line
			(start 1.524 -0.762)
			(end -1.524 -0.762)
			(stroke
				(width 0.1524)
				(type default)
			)
			(layer "B.SilkS")
		)
		(fp_line
			(start 1.524 0.762)
			(end 1.524 -0.762)
			(stroke
				(width 0.1524)
				(type default)
			)
			(layer "B.SilkS")
		)
		(fp_line
			(start -1.1049 -0.724916)
			(end 1.1049 -0.724916)
			(stroke
				(width 0.1)
				(type default)
			)
			(layer "B.Fab")
		)
		(fp_line
			(start -1.1049 0.724916)
			(end -1.1049 -0.724916)
			(stroke
				(width 0.1)
				(type default)
			)
			(layer "B.Fab")
		)
		(fp_line
			(start 1.1049 -0.724916)
			(end 1.1049 0.724916)
			(stroke
				(width 0.1)
				(type default)
			)
			(layer "B.Fab")
		)
		(fp_line
			(start 1.1049 0.724916)
			(end -1.1049 0.724916)
			(stroke
				(width 0.1)
				(type default)
			)
			(layer "B.Fab")
		)
		(pad "1" smd rect
			(at 0.889 0)
			(size 1.016 1.27)
			(layers "B.Cu" "B.Mask" "B.Paste")
			(net "SW_P12V_AUX_PVDD11_S3_P1_FLT")
		)
		(pad "2" smd rect
			(at -0.889 0)
			(size 1.016 1.27)
			(layers "B.Cu" "B.Mask" "B.Paste")
			(net "GND")
		)
	)
	(footprint ""
		(layer "B.Cu")
		(at 43.576748 -194.987164 180)
		(property "Reference" "R1582"
			(at 0 0 0)
			(layer "B.SilkS")
			(hide yes)
			(effects
				(font
					(size 1.27 1.27)
				)
				(justify mirror)
			)
		)
		(property "Value" ""
			(at 0 0 0)
			(layer "B.Fab")
			(effects
				(font
					(size 1.27 1.27)
				)
				(justify mirror)
			)
		)
		(duplicate_pad_numbers_are_jumpers no)
		(fp_line
			(start 0.7874 0.4064)
			(end 0.7874 -0.4064)
			(stroke
				(width 0.1524)
				(type default)
			)
			(layer "B.SilkS")
		)
		(fp_line
			(start 0.7874 -0.4064)
			(end -0.7874 -0.4064)
			(stroke
				(width 0.1524)
				(type default)
			)
			(layer "B.SilkS")
		)
		(fp_line
			(start -0.7874 0.4064)
			(end 0.7874 0.4064)
			(stroke
				(width 0.1524)
				(type default)
			)
			(layer "B.SilkS")
		)
		(fp_line
			(start -0.7874 -0.4064)
			(end -0.7874 0.4064)
			(stroke
				(width 0.1524)
				(type default)
			)
			(layer "B.SilkS")
		)
		(fp_line
			(start 0.67945 0.3048)
			(end 0.67945 -0.305054)
			(stroke
				(width 0.1)
				(type default)
			)
			(layer "B.Fab")
		)
		(fp_line
			(start 0.67945 -0.305054)
			(end 0.12065 -0.305054)
			(stroke
				(width 0.1)
				(type default)
			)
			(layer "B.Fab")
		)
		(fp_line
			(start 0.12065 0.3048)
			(end 0.67945 0.3048)
			(stroke
				(width 0.1)
				(type default)
			)
			(layer "B.Fab")
		)
		(fp_line
			(start 0.12065 0.2794)
			(end 0.12065 0.3048)
			(stroke
				(width 0.1)
				(type default)
			)
			(layer "B.Fab")
		)
		(fp_line
			(start 0.12065 -0.2794)
			(end -0.12065 -0.2794)
			(stroke
				(width 0.1)
				(type default)
			)
			(layer "B.Fab")
		)
		(fp_line
			(start 0.12065 -0.305054)
			(end 0.12065 -0.2794)
			(stroke
				(width 0.1)
				(type default)
			)
			(layer "B.Fab")
		)
		(fp_line
			(start -0.120396 0.3048)
			(end -0.120396 0.2794)
			(stroke
				(width 0.1)
				(type default)
			)
			(layer "B.Fab")
		)
		(fp_line
			(start -0.120396 0.2794)
			(end 0.12065 0.2794)
			(stroke
				(width 0.1)
				(type default)
			)
			(layer "B.Fab")
		)
		(fp_line
			(start -0.12065 -0.2794)
			(end -0.12065 -0.3048)
			(stroke
				(width 0.1)
				(type default)
			)
			(layer "B.Fab")
		)
		(fp_line
			(start -0.12065 -0.3048)
			(end -0.67945 -0.3048)
			(stroke
				(width 0.1)
				(type default)
			)
			(layer "B.Fab")
		)
		(fp_line
			(start -0.67945 0.3048)
			(end -0.120396 0.3048)
			(stroke
				(width 0.1)
				(type default)
			)
			(layer "B.Fab")
		)
		(fp_line
			(start -0.67945 -0.3048)
			(end -0.67945 0.3048)
			(stroke
				(width 0.1)
				(type default)
			)
			(layer "B.Fab")
		)
		(pad "1" smd circle
			(at 0.40005 0)
			(size 0 0)
			(layers "B.Cu" "B.Mask" "B.Paste")
			(net "I3C_SPD_DDRAF_CPU1_SCL")
		)
		(pad "2" smd circle
			(at -0.40005 0)
			(size 0 0)
			(layers "B.Cu" "B.Mask" "B.Paste")
			(net "I3C_SPD_DDRC_CPU1_SCL")
		)
	)
	(footprint ""
		(layer "B.Cu")
		(at 406.698958 -324.862952)
		(property "Reference" "R455"
			(at 0 0 0)
			(layer "B.SilkS")
			(hide yes)
			(effects
				(font
					(size 1.27 1.27)
				)
				(justify mirror)
			)
		)
		(property "Value" ""
			(at 0 0 0)
			(layer "B.Fab")
			(effects
				(font
					(size 1.27 1.27)
				)
				(justify mirror)
			)
		)
		(duplicate_pad_numbers_are_jumpers no)
		(fp_line
			(start -0.7874 -0.4064)
			(end -0.7874 0.4064)
			(stroke
				(width 0.1524)
				(type default)
			)
			(layer "B.SilkS")
		)
		(fp_line
			(start -0.7874 0.4064)
			(end 0.7874 0.4064)
			(stroke
				(width 0.1524)
				(type default)
			)
			(layer "B.SilkS")
		)
		(fp_line
			(start 0.7874 -0.4064)
			(end -0.7874 -0.4064)
			(stroke
				(width 0.1524)
				(type default)
			)
			(layer "B.SilkS")
		)
		(fp_line
			(start 0.7874 0.4064)
			(end 0.7874 -0.4064)
			(stroke
				(width 0.1524)
				(type default)
			)
			(layer "B.SilkS")
		)
		(fp_line
			(start -0.67945 -0.3048)
			(end -0.67945 0.3048)
			(stroke
				(width 0.1)
				(type default)
			)
			(layer "B.Fab")
		)
		(fp_line
			(start -0.67945 0.3048)
			(end -0.120396 0.3048)
			(stroke
				(width 0.1)
				(type default)
			)
			(layer "B.Fab")
		)
		(fp_line
			(start -0.12065 -0.3048)
			(end -0.67945 -0.3048)
			(stroke
				(width 0.1)
				(type default)
			)
			(layer "B.Fab")
		)
		(fp_line
			(start -0.12065 -0.2794)
			(end -0.12065 -0.3048)
			(stroke
				(width 0.1)
				(type default)
			)
			(layer "B.Fab")
		)
		(fp_line
			(start -0.120396 0.2794)
			(end 0.12065 0.2794)
			(stroke
				(width 0.1)
				(type default)
			)
			(layer "B.Fab")
		)
		(fp_line
			(start -0.120396 0.3048)
			(end -0.120396 0.2794)
			(stroke
				(width 0.1)
				(type default)
			)
			(layer "B.Fab")
		)
		(fp_line
			(start 0.12065 -0.305054)
			(end 0.12065 -0.2794)
			(stroke
				(width 0.1)
				(type default)
			)
			(layer "B.Fab")
		)
		(fp_line
			(start 0.12065 -0.2794)
			(end -0.12065 -0.2794)
			(stroke
				(width 0.1)
				(type default)
			)
			(layer "B.Fab")
		)
		(fp_line
			(start 0.12065 0.2794)
			(end 0.12065 0.3048)
			(stroke
				(width 0.1)
				(type default)
			)
			(layer "B.Fab")
		)
		(fp_line
			(start 0.12065 0.3048)
			(end 0.67945 0.3048)
			(stroke
				(width 0.1)
				(type default)
			)
			(layer "B.Fab")
		)
		(fp_line
			(start 0.67945 -0.305054)
			(end 0.12065 -0.305054)
			(stroke
				(width 0.1)
				(type default)
			)
			(layer "B.Fab")
		)
		(fp_line
			(start 0.67945 0.3048)
			(end 0.67945 -0.305054)
			(stroke
				(width 0.1)
				(type default)
			)
			(layer "B.Fab")
		)
		(pad "1" smd circle
			(at 0.40005 0 180)
			(size 0 0)
			(layers "B.Cu" "B.Mask" "B.Paste")
			(net "PVDD18_S5_P0")
		)
		(pad "2" smd circle
			(at -0.40005 0 180)
			(size 0 0)
			(layers "B.Cu" "B.Mask" "B.Paste")
			(net "ESPI_CPU0_CS1_N")
		)
	)
)
